# SCM (Grand Teton) — schematic netlist excerpt (pin names and nets, part order shuffled) for the footprints in the layout excerpt that follows; sources: Cadence DE-HDL packaged netlist, KiCad conversion of 12092022_DA0F0TMDCD0_F0T_Management_Board_D_brd_V3_OCP.brd

R74  Q_RES  2K 1% CHIP  pkg 0402LF  page 11 : A = P3V3_AUX ; B = SGPIO_DI_1
PC224  Q_CAP  0.22UF 16V 10% X7R  pkg 0402  page 52 : A = SW_P3V3_AUX_BST ; B = SW_P3V3_AUX_SW

(kicad_pcb
	(version 20260206)
	(generator "pcbnew")
	(generator_version "10.0")
	(general
		(thickness 1.6)
		(legacy_teardrops no)
	)
	(paper "A4")
	(title_block
		(title "12092022_DA0F0TMDCD0_F0T_Management_Board_D_brd_V3_OCP.brd")
		(comment 1 "Grand Teton / footprints 7-8 of 1440")
	)
	(layers
		(0 "F.Cu" signal "TOP")
		(4 "In1.Cu" signal "GND")
		(6 "In2.Cu" signal "IN1")
		(8 "In3.Cu" signal "GND1")
		(10 "In4.Cu" signal "IN2")
		(12 "In5.Cu" signal "VCC")
		(14 "In6.Cu" signal "VCC1")
		(16 "In7.Cu" signal "IN3")
		(18 "In8.Cu" signal "GND2")
		(20 "In9.Cu" signal "IN4")
		(22 "In10.Cu" signal "GND3")
		(2 "B.Cu" signal "BOTTOM")
		(9 "F.Adhes" user "F.Adhesive")
		(11 "B.Adhes" user "B.Adhesive")
		(13 "F.Paste" user "Package Geometry/Pastemask Top")
		(15 "B.Paste" user "Package Geometry/Pastemask Bottom")
		(5 "F.SilkS" user "Ref Des/Silkscreen Top")
		(7 "B.SilkS" user "Ref Des/Silkscreen Bottom")
		(1 "F.Mask" user "Board Geometry/Soldermask Top")
		(3 "B.Mask" user "Board Geometry/Soldermask Bottom")
		(17 "Dwgs.User" user "User.Drawings")
		(19 "Cmts.User" user "User.Comments")
		(21 "Eco1.User" user "User.Eco1")
		(23 "Eco2.User" user "User.Eco2")
		(25 "Edge.Cuts" user "Board Geometry/Outline")
		(27 "Margin" user)
		(31 "F.CrtYd" user "Package Geometry/Place Bound Top")
		(29 "B.CrtYd" user "Package Geometry/Place Bound Bottom")
		(35 "F.Fab" user "Ref Des/Assembly Top")
		(33 "B.Fab" user "Ref Des/Assembly Bottom")
	)
	(footprint ""
		(layer "F.Cu")
		(at 36.8808 -109.4613 -90)
		(property "Reference" "R74"
			(at 0 0 270)
			(layer "F.SilkS")
			(hide yes)
			(effects
				(font
					(size 1.27 1.27)
				)
			)
		)
		(property "Value" ""
			(at 0 0 270)
			(layer "F.Fab")
			(effects
				(font
					(size 1.27 1.27)
				)
			)
		)
		(duplicate_pad_numbers_are_jumpers no)
		(fp_line
			(start -0.7874 0.4064)
			(end -0.7874 -0.4064)
			(stroke
				(width 0.1524)
				(type default)
			)
			(layer "F.SilkS")
		)
		(fp_line
			(start 0.7874 0.4064)
			(end -0.7874 0.4064)
			(stroke
				(width 0.1524)
				(type default)
			)
			(layer "F.SilkS")
		)
		(fp_line
			(start -0.7874 -0.4064)
			(end 0.7874 -0.4064)
			(stroke
				(width 0.1524)
				(type default)
			)
			(layer "F.SilkS")
		)
		(fp_line
			(start 0.7874 -0.4064)
			(end 0.7874 0.4064)
			(stroke
				(width 0.1524)
				(type default)
			)
			(layer "F.SilkS")
		)
		(fp_line
			(start -0.67945 0.3048)
			(end -0.67945 -0.305054)
			(stroke
				(width 0.1)
				(type default)
			)
			(layer "F.Fab")
		)
		(fp_line
			(start -0.12065 0.3048)
			(end -0.67945 0.3048)
			(stroke
				(width 0.1)
				(type default)
			)
			(layer "F.Fab")
		)
		(fp_line
			(start 0.120396 0.3048)
			(end 0.120396 0.2794)
			(stroke
				(width 0.1)
				(type default)
			)
			(layer "F.Fab")
		)
		(fp_line
			(start 0.67945 0.3048)
			(end 0.120396 0.3048)
			(stroke
				(width 0.1)
				(type default)
			)
			(layer "F.Fab")
		)
		(fp_line
			(start -0.12065 0.2794)
			(end -0.12065 0.3048)
			(stroke
				(width 0.1)
				(type default)
			)
			(layer "F.Fab")
		)
		(fp_line
			(start 0.120396 0.2794)
			(end -0.12065 0.2794)
			(stroke
				(width 0.1)
				(type default)
			)
			(layer "F.Fab")
		)
		(fp_line
			(start -0.12065 -0.2794)
			(end 0.12065 -0.2794)
			(stroke
				(width 0.1)
				(type default)
			)
			(layer "F.Fab")
		)
		(fp_line
			(start 0.12065 -0.2794)
			(end 0.12065 -0.3048)
			(stroke
				(width 0.1)
				(type default)
			)
			(layer "F.Fab")
		)
		(fp_line
			(start 0.12065 -0.3048)
			(end 0.67945 -0.3048)
			(stroke
				(width 0.1)
				(type default)
			)
			(layer "F.Fab")
		)
		(fp_line
			(start 0.67945 -0.3048)
			(end 0.67945 0.3048)
			(stroke
				(width 0.1)
				(type default)
			)
			(layer "F.Fab")
		)
		(fp_line
			(start -0.67945 -0.305054)
			(end -0.12065 -0.305054)
			(stroke
				(width 0.1)
				(type default)
			)
			(layer "F.Fab")
		)
		(fp_line
			(start -0.12065 -0.305054)
			(end -0.12065 -0.2794)
			(stroke
				(width 0.1)
				(type default)
			)
			(layer "F.Fab")
		)
		(pad "1" smd circle
			(at -0.40005 0 270)
			(size 0 0)
			(layers "F.Cu" "F.Mask" "F.Paste")
			(net "P3V3_AUX")
		)
		(pad "2" smd circle
			(at 0.40005 0 270)
			(size 0 0)
			(layers "F.Cu" "F.Mask" "F.Paste")
			(net "SGPIO_DI_1")
		)
	)
	(footprint ""
		(layer "F.Cu")
		(at 7.4422 -67.183 180)
		(property "Reference" "PC224"
			(at 0 0 180)
			(layer "F.SilkS")
			(hide yes)
			(effects
				(font
					(size 1.27 1.27)
				)
			)
		)
		(property "Value" ""
			(at 0 0 180)
			(layer "F.Fab")
			(effects
				(font
					(size 1.27 1.27)
				)
			)
		)
		(duplicate_pad_numbers_are_jumpers no)
		(fp_line
			(start 0.7874 0.4064)
			(end -0.7874 0.4064)
			(stroke
				(width 0.1524)
				(type default)
			)
			(layer "F.SilkS")
		)
		(fp_line
			(start 0.7874 -0.4064)
			(end 0.7874 0.4064)
			(stroke
				(width 0.1524)
				(type default)
			)
			(layer "F.SilkS")
		)
		(fp_line
			(start -0.7874 0.4064)
			(end -0.7874 -0.4064)
			(stroke
				(width 0.1524)
				(type default)
			)
			(layer "F.SilkS")
		)
		(fp_line
			(start -0.7874 -0.4064)
			(end 0.7874 -0.4064)
			(stroke
				(width 0.1524)
				(type default)
			)
			(layer "F.SilkS")
		)
		(fp_line
			(start 0.67945 0.3048)
			(end 0.120396 0.3048)
			(stroke
				(width 0.1)
				(type default)
			)
			(layer "F.Fab")
		)
		(fp_line
			(start 0.67945 -0.3048)
			(end 0.67945 0.3048)
			(stroke
				(width 0.1)
				(type default)
			)
			(layer "F.Fab")
		)
		(fp_line
			(start 0.12065 -0.2794)
			(end 0.12065 -0.3048)
			(stroke
				(width 0.1)
				(type default)
			)
			(layer "F.Fab")
		)
		(fp_line
			(start 0.12065 -0.3048)
			(end 0.67945 -0.3048)
			(stroke
				(width 0.1)
				(type default)
			)
			(layer "F.Fab")
		)
		(fp_line
			(start 0.120396 0.3048)
			(end 0.120396 0.2794)
			(stroke
				(width 0.1)
				(type default)
			)
			(layer "F.Fab")
		)
		(fp_line
			(start 0.120396 0.2794)
			(end -0.12065 0.2794)
			(stroke
				(width 0.1)
				(type default)
			)
			(layer "F.Fab")
		)
		(fp_line
			(start -0.12065 0.3048)
			(end -0.67945 0.3048)
			(stroke
				(width 0.1)
				(type default)
			)
			(layer "F.Fab")
		)
		(fp_line
			(start -0.12065 0.2794)
			(end -0.12065 0.3048)
			(stroke
				(width 0.1)
				(type default)
			)
			(layer "F.Fab")
		)
		(fp_line
			(start -0.12065 -0.2794)
			(end 0.12065 -0.2794)
			(stroke
				(width 0.1)
				(type default)
			)
			(layer "F.Fab")
		)
		(fp_line
			(start -0.12065 -0.305054)
			(end -0.12065 -0.2794)
			(stroke
				(width 0.1)
				(type default)
			)
			(layer "F.Fab")
		)
		(fp_line
			(start -0.67945 0.3048)
			(end -0.67945 -0.305054)
			(stroke
				(width 0.1)
				(type default)
			)
			(layer "F.Fab")
		)
		(fp_line
			(start -0.67945 -0.305054)
			(end -0.12065 -0.305054)
			(stroke
				(width 0.1)
				(type default)
			)
			(layer "F.Fab")
		)
		(pad "1" smd circle
			(at -0.40005 0 180)
			(size 0 0)
			(layers "F.Cu" "F.Mask" "F.Paste")
			(net "SW_P3V3_AUX_BST")
		)
		(pad "2" smd circle
			(at 0.40005 0 180)
			(size 0 0)
			(layers "F.Cu" "F.Mask" "F.Paste")
			(net "SW_P3V3_AUX_SW")
		)
	)
)
